(kicad_pcb
	(version 20241229)
	(generator "pcbnew")
	(generator_version "9.0")
	(general
		(thickness 1.6)
		(legacy_teardrops no)
	)
	(paper "A4")
	(title_block
		(title "GMSL Deserializer")
		(date "2025-10-09")
		(rev "1.0.4")
		(company "Antmicro Ltd")
		(comment 1 "www.antmicro.com")
		(comment 9 "footprints 181-185 of 235")
	)
	(layers
		(0 "F.Cu" signal)
		(4 "In1.Cu" power)
		(6 "In2.Cu" power)
		(2 "B.Cu" signal)
		(9 "F.Adhes" user "F.Adhesive")
		(11 "B.Adhes" user "B.Adhesive")
		(13 "F.Paste" user)
		(15 "B.Paste" user)
		(5 "F.SilkS" user "F.Silkscreen")
		(7 "B.SilkS" user "B.Silkscreen")
		(1 "F.Mask" user)
		(3 "B.Mask" user)
		(17 "Dwgs.User" user "User.Drawings")
		(19 "Cmts.User" user "User.Comments")
		(21 "Eco1.User" user "User.Eco1")
		(23 "Eco2.User" user "User.Eco2")
		(25 "Edge.Cuts" user)
		(27 "Margin" user)
		(31 "F.CrtYd" user "F.Courtyard")
		(29 "B.CrtYd" user "B.Courtyard")
		(35 "F.Fab" user)
		(33 "B.Fab" user)
	)
	(footprint "antmicro-footprints:C_0402_1005Metric"
		(layer "B.Cu")
		(at 153.67 82.55 135)
		(descr "Capacitor SMD 0402")
		(tags "capacitor SMD 0402")
		(property "Reference" "C46"
			(at -1.271377 0.032325 315)
			(unlocked yes)
			(layer "B.SilkS")
			(effects
				(font
					(size 0.7 0.7)
					(thickness 0.15)
				)
				(justify right bottom mirror)
			)
		)
		(property "Value" "C_100n_0402"
			(at -1.022927 -2.155213 135)
			(layer "B.Fab")
			(effects
				(font
					(size 0.7 0.7)
					(thickness 0.15)
				)
				(justify right bottom mirror)
			)
		)
		(property "Datasheet" "https://www.murata.com/products/productdetail?partno=GRM155R61H104KE14%23"
			(at 0 0 135)
			(layer "F.Fab")
			(hide yes)
			(effects
				(font
					(size 1.27 1.27)
					(thickness 0.15)
				)
			)
		)
		(property "Description" "SMD Multilayer Ceramic Capacitor, 0.1 µF, 50 V, 0402 [1005 Metric], ± 10%, X5R, GRM Series"
			(at 0 0 135)
			(layer "F.Fab")
			(hide yes)
			(effects
				(font
					(size 1.27 1.27)
					(thickness 0.15)
				)
			)
		)
		(property "Author" "Antmicro"
			(at 320.702764 32.260566 0)
			(layer "B.Fab")
			(hide yes)
			(effects
				(font
					(size 1 1)
					(thickness 0.15)
				)
				(justify mirror)
			)
		)
		(property "Dielectric" "X5R"
			(at 320.702764 32.260566 0)
			(layer "B.Fab")
			(hide yes)
			(effects
				(font
					(size 1 1)
					(thickness 0.15)
				)
				(justify mirror)
			)
		)
		(property "License" "Apache-2.0"
			(at 320.702764 32.260566 0)
			(layer "B.Fab")
			(hide yes)
			(effects
				(font
					(size 1 1)
					(thickness 0.15)
				)
				(justify mirror)
			)
		)
		(property "MPN" "GRM155R61H104KE14D"
			(at 320.702764 32.260566 0)
			(layer "B.Fab")
			(hide yes)
			(effects
				(font
					(size 1 1)
					(thickness 0.15)
				)
				(justify mirror)
			)
		)
		(property "Manufacturer" "Murata"
			(at 320.702764 32.260566 0)
			(layer "B.Fab")
			(hide yes)
			(effects
				(font
					(size 1 1)
					(thickness 0.15)
				)
				(justify mirror)
			)
		)
		(property "Val" "100n"
			(at 320.702764 32.260566 0)
			(layer "B.Fab")
			(hide yes)
			(effects
				(font
					(size 1 1)
					(thickness 0.15)
				)
				(justify mirror)
			)
		)
		(property "Voltage" "50V"
			(at 320.702764 32.260566 0)
			(layer "B.Fab")
			(hide yes)
			(effects
				(font
					(size 1 1)
					(thickness 0.15)
				)
				(justify mirror)
			)
		)
		(sheetname "/Deserializer/")
		(sheetfile "deserializer.kicad_sch")
		(attr smd)
		(fp_poly
			(pts
				(xy -0.925 0.47) (xy 0.925 0.47) (xy 0.925 -0.47) (xy -0.925 -0.47)
			)
			(stroke
				(width 0.05)
				(type default)
			)
			(fill no)
			(layer "B.CrtYd")
		)
		(fp_line
			(start 0.504 -0.248)
			(end 0.504 0.25)
			(stroke
				(width 0.15)
				(type solid)
			)
			(layer "B.Fab")
		)
		(fp_line
			(start 0.504 0.25)
			(end -0.494 0.25)
			(stroke
				(width 0.15)
				(type solid)
			)
			(layer "B.Fab")
		)
		(fp_line
			(start -0.494 -0.248)
			(end 0.504 -0.248)
			(stroke
				(width 0.15)
				(type solid)
			)
			(layer "B.Fab")
		)
		(fp_line
			(start -0.494 0.25)
			(end -0.494 -0.248)
			(stroke
				(width 0.15)
				(type solid)
			)
			(layer "B.Fab")
		)
		(pad "1" smd roundrect
			(at -0.48 0 135)
			(size 0.59 0.64)
			(layers "B.Cu" "B.Mask" "B.Paste")
			(roundrect_rratio 0.25)
			(net 1 "GND")
			(pintype "passive")
		)
		(pad "2" smd roundrect
			(at 0.48 0 135)
			(size 0.59 0.64)
			(layers "B.Cu" "B.Mask" "B.Paste")
			(roundrect_rratio 0.25)
			(net 27 "/Deserializer/VDD")
			(pintype "passive")
		)
	)
	(footprint "antmicro-footprints:C_0402_1005Metric"
		(layer "B.Cu")
		(at 144.272 75.692 -45)
		(descr "Capacitor SMD 0402")
		(tags "capacitor SMD 0402")
		(property "Reference" "C38"
			(at -1.51371 0.22729 315)
			(unlocked yes)
			(layer "B.SilkS")
			(effects
				(font
					(size 0.7 0.7)
					(thickness 0.15)
				)
				(justify left bottom mirror)
			)
		)
		(property "Value" "C_10u_0402"
			(at -1.022927 -2.155213 135)
			(layer "B.Fab")
			(effects
				(font
					(size 0.7 0.7)
					(thickness 0.15)
				)
				(justify left bottom mirror)
			)
		)
		(property "Datasheet" "https://www.yageo.com/en/Chart/Download/pdf/CC0402MRX5R5BB106"
			(at 0 0 315)
			(layer "F.Fab")
			(hide yes)
			(effects
				(font
					(size 1.27 1.27)
					(thickness 0.15)
				)
			)
		)
		(property "Description" "SMD Multilayer Ceramic Capacitor, 10 µF, 6.3 V, 0402 [1005 Metric], ± 20%, X5R, CC Series"
			(at 0 0 315)
			(layer "F.Fab")
			(hide yes)
			(effects
				(font
					(size 1.27 1.27)
					(thickness 0.15)
				)
			)
		)
		(property "Author" "Antmicro"
			(at -11.266036 124.185383 0)
			(layer "B.Fab")
			(hide yes)
			(effects
				(font
					(size 1 1)
					(thickness 0.15)
				)
				(justify mirror)
			)
		)
		(property "Dielectric" ""
			(at -11.266036 124.185383 0)
			(layer "B.Fab")
			(hide yes)
			(effects
				(font
					(size 1 1)
					(thickness 0.15)
				)
				(justify mirror)
			)
		)
		(property "License" "Apache-2.0"
			(at -11.266036 124.185383 0)
			(layer "B.Fab")
			(hide yes)
			(effects
				(font
					(size 1 1)
					(thickness 0.15)
				)
				(justify mirror)
			)
		)
		(property "MPN" "CC0402MRX5R5BB106"
			(at -11.266036 124.185383 0)
			(layer "B.Fab")
			(hide yes)
			(effects
				(font
					(size 1 1)
					(thickness 0.15)
				)
				(justify mirror)
			)
		)
		(property "Manufacturer" "YAGEO"
			(at -11.266036 124.185383 0)
			(layer "B.Fab")
			(hide yes)
			(effects
				(font
					(size 1 1)
					(thickness 0.15)
				)
				(justify mirror)
			)
		)
		(property "Val" "10u"
			(at -11.266036 124.185383 0)
			(layer "B.Fab")
			(hide yes)
			(effects
				(font
					(size 1 1)
					(thickness 0.15)
				)
				(justify mirror)
			)
		)
		(property "Voltage" ""
			(at -11.266036 124.185383 0)
			(layer "B.Fab")
			(hide yes)
			(effects
				(font
					(size 1 1)
					(thickness 0.15)
				)
				(justify mirror)
			)
		)
		(sheetname "/Deserializer/")
		(sheetfile "deserializer.kicad_sch")
		(attr smd)
		(fp_poly
			(pts
				(xy -0.925 0.47) (xy 0.925 0.47) (xy 0.925 -0.47) (xy -0.925 -0.47)
			)
			(stroke
				(width 0.05)
				(type default)
			)
			(fill no)
			(layer "B.CrtYd")
		)
		(fp_line
			(start -0.494 0.25)
			(end -0.494 -0.248)
			(stroke
				(width 0.15)
				(type solid)
			)
			(layer "B.Fab")
		)
		(fp_line
			(start -0.494 -0.248)
			(end 0.504 -0.248)
			(stroke
				(width 0.15)
				(type solid)
			)
			(layer "B.Fab")
		)
		(fp_line
			(start 0.504 0.25)
			(end -0.494 0.25)
			(stroke
				(width 0.15)
				(type solid)
			)
			(layer "B.Fab")
		)
		(fp_line
			(start 0.504 -0.248)
			(end 0.504 0.25)
			(stroke
				(width 0.15)
				(type solid)
			)
			(layer "B.Fab")
		)
		(pad "1" smd roundrect
			(at -0.48 0 315)
			(size 0.59 0.64)
			(layers "B.Cu" "B.Mask" "B.Paste")
			(roundrect_rratio 0.25)
			(net 1 "GND")
			(pintype "passive")
		)
		(pad "2" smd roundrect
			(at 0.48 0 315)
			(size 0.59 0.64)
			(layers "B.Cu" "B.Mask" "B.Paste")
			(roundrect_rratio 0.25)
			(net 28 "/Deserializer/CAP_VDD")
			(pintype "passive")
		)
	)
	(footprint "antmicro-footprints:C_0402_1005Metric"
		(layer "B.Cu")
		(at 152.908 83.312 135)
		(descr "Capacitor SMD 0402")
		(tags "capacitor SMD 0402")
		(property "Reference" "C43"
			(at -0.97797 -1.314712 315)
			(unlocked yes)
			(layer "B.SilkS")
			(effects
				(font
					(size 0.7 0.7)
					(thickness 0.15)
				)
				(justify right bottom mirror)
			)
		)
		(property "Value" "C_10n_0402"
			(at -1.022927 -2.155213 135)
			(layer "B.Fab")
			(effects
				(font
					(size 0.7 0.7)
					(thickness 0.15)
				)
				(justify right bottom mirror)
			)
		)
		(property "Datasheet" "https://www.murata.com/products/productdetail?partno=GRM155R71H103KA88%23"
			(at 0 0 135)
			(layer "F.Fab")
			(hide yes)
			(effects
				(font
					(size 1.27 1.27)
					(thickness 0.15)
				)
			)
		)
		(property "Description" "SMD Multilayer Ceramic Capacitor, 10000 pF, 50 V, 0402 [1005 Metric], ± 10%, X7R, GRM Series"
			(at 0 0 135)
			(layer "F.Fab")
			(hide yes)
			(effects
				(font
					(size 1.27 1.27)
					(thickness 0.15)
				)
			)
		)
		(property "Author" "Antmicro"
			(at 319.940764 34.100196 0)
			(layer "B.Fab")
			(hide yes)
			(effects
				(font
					(size 1 1)
					(thickness 0.15)
				)
				(justify mirror)
			)
		)
		(property "Dielectric" "X7R"
			(at 319.940764 34.100196 0)
			(layer "B.Fab")
			(hide yes)
			(effects
				(font
					(size 1 1)
					(thickness 0.15)
				)
				(justify mirror)
			)
		)
		(property "License" "Apache-2.0"
			(at 319.940764 34.100196 0)
			(layer "B.Fab")
			(hide yes)
			(effects
				(font
					(size 1 1)
					(thickness 0.15)
				)
				(justify mirror)
			)
		)
		(property "MPN" "GRM155R71H103KA88D"
			(at 319.940764 34.100196 0)
			(layer "B.Fab")
			(hide yes)
			(effects
				(font
					(size 1 1)
					(thickness 0.15)
				)
				(justify mirror)
			)
		)
		(property "Manufacturer" "Murata"
			(at 319.940764 34.100196 0)
			(layer "B.Fab")
			(hide yes)
			(effects
				(font
					(size 1 1)
					(thickness 0.15)
				)
				(justify mirror)
			)
		)
		(property "Val" "10n"
			(at 319.940764 34.100196 0)
			(layer "B.Fab")
			(hide yes)
			(effects
				(font
					(size 1 1)
					(thickness 0.15)
				)
				(justify mirror)
			)
		)
		(property "Voltage" "50V"
			(at 319.940764 34.100196 0)
			(layer "B.Fab")
			(hide yes)
			(effects
				(font
					(size 1 1)
					(thickness 0.15)
				)
				(justify mirror)
			)
		)
		(sheetname "/Deserializer/")
		(sheetfile "deserializer.kicad_sch")
		(attr smd)
		(fp_poly
			(pts
				(xy -0.925 0.47) (xy 0.925 0.47) (xy 0.925 -0.47) (xy -0.925 -0.47)
			)
			(stroke
				(width 0.05)
				(type default)
			)
			(fill no)
			(layer "B.CrtYd")
		)
		(fp_line
			(start 0.504 -0.248)
			(end 0.504 0.25)
			(stroke
				(width 0.15)
				(type solid)
			)
			(layer "B.Fab")
		)
		(fp_line
			(start 0.504 0.25)
			(end -0.494 0.25)
			(stroke
				(width 0.15)
				(type solid)
			)
			(layer "B.Fab")
		)
		(fp_line
			(start -0.494 -0.248)
			(end 0.504 -0.248)
			(stroke
				(width 0.15)
				(type solid)
			)
			(layer "B.Fab")
		)
		(fp_line
			(start -0.494 0.25)
			(end -0.494 -0.248)
			(stroke
				(width 0.15)
				(type solid)
			)
			(layer "B.Fab")
		)
		(pad "1" smd roundrect
			(at -0.48 0 135)
			(size 0.59 0.64)
			(layers "B.Cu" "B.Mask" "B.Paste")
			(roundrect_rratio 0.25)
			(net 1 "GND")
			(pintype "passive")
		)
		(pad "2" smd roundrect
			(at 0.48 0 135)
			(size 0.59 0.64)
			(layers "B.Cu" "B.Mask" "B.Paste")
			(roundrect_rratio 0.25)
			(net 27 "/Deserializer/VDD")
			(pintype "passive")
		)
	)
	(footprint "antmicro-footprints:C_0402_1005Metric"
		(layer "B.Cu")
		(at 139.192 80.772 -45)
		(descr "Capacitor SMD 0402")
		(tags "capacitor SMD 0402")
		(property "Reference" "C50"
			(at -1.660511 0.317093 315)
			(unlocked yes)
			(layer "B.SilkS")
			(effects
				(font
					(size 0.7 0.7)
					(thickness 0.15)
				)
				(justify left bottom mirror)
			)
		)
		(property "Value" "C_10n_0402"
			(at -1.022927 -2.155213 135)
			(layer "B.Fab")
			(effects
				(font
					(size 0.7 0.7)
					(thickness 0.15)
				)
				(justify left bottom mirror)
			)
		)
		(property "Datasheet" "https://www.murata.com/products/productdetail?partno=GRM155R71H103KA88%23"
			(at 0 0 315)
			(layer "F.Fab")
			(hide yes)
			(effects
				(font
					(size 1.27 1.27)
					(thickness 0.15)
				)
			)
		)
		(property "Description" "SMD Multilayer Ceramic Capacitor, 10000 pF, 50 V, 0402 [1005 Metric], ± 10%, X7R, GRM Series"
			(at 0 0 315)
			(layer "F.Fab")
			(hide yes)
			(effects
				(font
					(size 1.27 1.27)
					(thickness 0.15)
				)
			)
		)
		(property "Author" "Antmicro"
			(at -16.346036 122.081178 0)
			(layer "B.Fab")
			(hide yes)
			(effects
				(font
					(size 1 1)
					(thickness 0.15)
				)
				(justify mirror)
			)
		)
		(property "Dielectric" "X7R"
			(at -16.346036 122.081178 0)
			(layer "B.Fab")
			(hide yes)
			(effects
				(font
					(size 1 1)
					(thickness 0.15)
				)
				(justify mirror)
			)
		)
		(property "License" "Apache-2.0"
			(at -16.346036 122.081178 0)
			(layer "B.Fab")
			(hide yes)
			(effects
				(font
					(size 1 1)
					(thickness 0.15)
				)
				(justify mirror)
			)
		)
		(property "MPN" "GRM155R71H103KA88D"
			(at -16.346036 122.081178 0)
			(layer "B.Fab")
			(hide yes)
			(effects
				(font
					(size 1 1)
					(thickness 0.15)
				)
				(justify mirror)
			)
		)
		(property "Manufacturer" "Murata"
			(at -16.346036 122.081178 0)
			(layer "B.Fab")
			(hide yes)
			(effects
				(font
					(size 1 1)
					(thickness 0.15)
				)
				(justify mirror)
			)
		)
		(property "Val" "10n"
			(at -16.346036 122.081178 0)
			(layer "B.Fab")
			(hide yes)
			(effects
				(font
					(size 1 1)
					(thickness 0.15)
				)
				(justify mirror)
			)
		)
		(property "Voltage" "50V"
			(at -16.346036 122.081178 0)
			(layer "B.Fab")
			(hide yes)
			(effects
				(font
					(size 1 1)
					(thickness 0.15)
				)
				(justify mirror)
			)
		)
		(sheetname "/Deserializer/")
		(sheetfile "deserializer.kicad_sch")
		(attr smd)
		(fp_poly
			(pts
				(xy -0.925 0.47) (xy 0.925 0.47) (xy 0.925 -0.47) (xy -0.925 -0.47)
			)
			(stroke
				(width 0.05)
				(type default)
			)
			(fill no)
			(layer "B.CrtYd")
		)
		(fp_line
			(start -0.494 0.25)
			(end -0.494 -0.248)
			(stroke
				(width 0.15)
				(type solid)
			)
			(layer "B.Fab")
		)
		(fp_line
			(start -0.494 -0.248)
			(end 0.504 -0.248)
			(stroke
				(width 0.15)
				(type solid)
			)
			(layer "B.Fab")
		)
		(fp_line
			(start 0.504 0.25)
			(end -0.494 0.25)
			(stroke
				(width 0.15)
				(type solid)
			)
			(layer "B.Fab")
		)
		(fp_line
			(start 0.504 -0.248)
			(end 0.504 0.25)
			(stroke
				(width 0.15)
				(type solid)
			)
			(layer "B.Fab")
		)
		(pad "1" smd roundrect
			(at -0.48 0 315)
			(size 0.59 0.64)
			(layers "B.Cu" "B.Mask" "B.Paste")
			(roundrect_rratio 0.25)
			(net 1 "GND")
			(pintype "passive")
		)
		(pad "2" smd roundrect
			(at 0.48 0 315)
			(size 0.59 0.64)
			(layers "B.Cu" "B.Mask" "B.Paste")
			(roundrect_rratio 0.25)
			(net 146 "VDDIO")
			(pintype "passive")
		)
	)
	(footprint "antmicro-footprints:C_0402_1005Metric"
		(layer "B.Cu")
		(at 151.384 78.47374 -135)
		(descr "Capacitor SMD 0402")
		(tags "capacitor SMD 0402")
		(property "Reference" "C48"
			(at -3.690905 -0.449013 45)
			(layer "B.SilkS")
			(effects
				(font
					(size 0.7 0.7)
					(thickness 0.15)
				)
				(justify left bottom mirror)
			)
		)
		(property "Value" "C_10n_0402"
			(at -1.022927 -2.155213 45)
			(layer "B.Fab")
			(effects
				(font
					(size 0.7 0.7)
					(thickness 0.15)
				)
				(justify left bottom mirror)
			)
		)
		(property "Datasheet" "https://www.murata.com/products/productdetail?partno=GRM155R71H103KA88%23"
			(at 0 0 225)
			(layer "F.Fab")
			(hide yes)
			(effects
				(font
					(size 1.27 1.27)
					(thickness 0.15)
				)
			)
		)
		(property "Description" "SMD Multilayer Ceramic Capacitor, 10000 pF, 50 V, 0402 [1005 Metric], ± 10%, X7R, GRM Series"
			(at 0 0 225)
			(layer "F.Fab")
			(hide yes)
			(effects
				(font
					(size 1.27 1.27)
					(thickness 0.15)
				)
			)
		)
		(property "Author" "Antmicro"
			(at 202.939339 241.007707 0)
			(layer "B.Fab")
			(hide yes)
			(effects
				(font
					(size 1 1)
					(thickness 0.15)
				)
				(justify mirror)
			)
		)
		(property "Dielectric" "X7R"
			(at 202.939339 241.007707 0)
			(layer "B.Fab")
			(hide yes)
			(effects
				(font
					(size 1 1)
					(thickness 0.15)
				)
				(justify mirror)
			)
		)
		(property "License" "Apache-2.0"
			(at 202.939339 241.007707 0)
			(layer "B.Fab")
			(hide yes)
			(effects
				(font
					(size 1 1)
					(thickness 0.15)
				)
				(justify mirror)
			)
		)
		(property "MPN" "GRM155R71H103KA88D"
			(at 202.939339 241.007707 0)
			(layer "B.Fab")
			(hide yes)
			(effects
				(font
					(size 1 1)
					(thickness 0.15)
				)
				(justify mirror)
			)
		)
		(property "Manufacturer" "Murata"
			(at 202.939339 241.007707 0)
			(layer "B.Fab")
			(hide yes)
			(effects
				(font
					(size 1 1)
					(thickness 0.15)
				)
				(justify mirror)
			)
		)
		(property "Val" "10n"
			(at 202.939339 241.007707 0)
			(layer "B.Fab")
			(hide yes)
			(effects
				(font
					(size 1 1)
					(thickness 0.15)
				)
				(justify mirror)
			)
		)
		(property "Voltage" "50V"
			(at 202.939339 241.007707 0)
			(layer "B.Fab")
			(hide yes)
			(effects
				(font
					(size 1 1)
					(thickness 0.15)
				)
				(justify mirror)
			)
		)
		(sheetname "/Deserializer/")
		(sheetfile "deserializer.kicad_sch")
		(attr smd)
		(fp_poly
			(pts
				(xy -0.925 0.47) (xy 0.925 0.47) (xy 0.925 -0.47) (xy -0.925 -0.47)
			)
			(stroke
				(width 0.05)
				(type default)
			)
			(fill no)
			(layer "B.CrtYd")
		)
		(fp_line
			(start 0.504 0.25)
			(end -0.494 0.25)
			(stroke
				(width 0.15)
				(type solid)
			)
			(layer "B.Fab")
		)
		(fp_line
			(start 0.504 -0.248)
			(end 0.504 0.25)
			(stroke
				(width 0.15)
				(type solid)
			)
			(layer "B.Fab")
		)
		(fp_line
			(start -0.494 0.25)
			(end -0.494 -0.248)
			(stroke
				(width 0.15)
				(type solid)
			)
			(layer "B.Fab")
		)
		(fp_line
			(start -0.494 -0.248)
			(end 0.504 -0.248)
			(stroke
				(width 0.15)
				(type solid)
			)
			(layer "B.Fab")
		)
		(pad "1" smd roundrect
			(at -0.48 0 225)
			(size 0.59 0.64)
			(layers "B.Cu" "B.Mask" "B.Paste")
			(roundrect_rratio 0.25)
			(net 1 "GND")
			(pintype "passive")
		)
		(pad "2" smd roundrect
			(at 0.48 0 225)
			(size 0.59 0.64)
			(layers "B.Cu" "B.Mask" "B.Paste")
			(roundrect_rratio 0.25)
			(net 26 "/Deserializer/VDD_1.8V")
			(pintype "passive")
		)
	)
)
